(kicad_pcb
	(version 20241229)
	(generator "pcbnew")
	(generator_version "9.0")
	(general
		(thickness 1.294)
		(legacy_teardrops no)
	)
	(paper "A3")
	(title_block
		(title "Kintex 410T devboard")
		(date "2024-04-03")
		(rev "1.1.2")
		(comment 9 "footprints 42-44 of 975")
	)
	(layers
		(0 "F.Cu" mixed)
		(4 "In1.Cu" power)
		(6 "In2.Cu" power)
		(8 "In3.Cu" mixed)
		(10 "In4.Cu" power)
		(12 "In5.Cu" mixed)
		(14 "In6.Cu" power)
		(16 "In7.Cu" mixed)
		(18 "In8.Cu" power)
		(2 "B.Cu" mixed)
		(9 "F.Adhes" user "F.Adhesive")
		(11 "B.Adhes" user "B.Adhesive")
		(13 "F.Paste" user)
		(15 "B.Paste" user)
		(5 "F.SilkS" user "F.Silkscreen")
		(7 "B.SilkS" user "B.Silkscreen")
		(1 "F.Mask" user)
		(3 "B.Mask" user)
		(17 "Dwgs.User" user "User.Drawings")
		(19 "Cmts.User" user "User.Comments")
		(21 "Eco1.User" user "User.Eco1")
		(23 "Eco2.User" user "User.Eco2")
		(25 "Edge.Cuts" user)
		(27 "Margin" user)
		(31 "F.CrtYd" user "F.Courtyard")
		(29 "B.CrtYd" user "B.Courtyard")
		(35 "F.Fab" user)
		(33 "B.Fab" user)
	)
	(footprint "antmicro-footprints:QFN-32-1EP_5x5mm"
		(layer "F.Cu")
		(at 195.346 108.702)
		(property "Reference" "U19"
			(at -3.169 -3.12 0)
			(layer "F.SilkS")
			(effects
				(font
					(size 0.7 0.7)
					(thickness 0.15)
				)
				(justify left bottom)
			)
		)
		(property "Value" "MAX3421EETJ+"
			(at -4.939 3.91 0)
			(layer "F.Fab")
			(effects
				(font
					(size 0.7 0.7)
					(thickness 0.15)
				)
				(justify left bottom)
			)
		)
		(property "Description" "USB Interface, ESD-Protected USB Peripheral/Host Controller, USB 2.0, 3 V, 3.6 V, TQFN, 32 Pins"
			(at 0 0 0)
			(layer "F.Fab")
			(hide yes)
			(effects
				(font
					(size 1.27 1.27)
					(thickness 0.15)
				)
			)
		)
		(property "Author" "Antmicro"
			(at 0 0 0)
			(layer "F.Fab")
			(hide yes)
			(effects
				(font
					(size 1 1)
					(thickness 0.15)
				)
			)
		)
		(property "License" "Apache-2.0"
			(at 0 0 0)
			(layer "F.Fab")
			(hide yes)
			(effects
				(font
					(size 1 1)
					(thickness 0.15)
				)
			)
		)
		(property "MPN" "MAX3421EETJ+"
			(at 0 0 0)
			(layer "F.Fab")
			(hide yes)
			(effects
				(font
					(size 1 1)
					(thickness 0.15)
				)
			)
		)
		(property "Manufacturer" "Maxim Integrated Products"
			(at 0 0 0)
			(layer "F.Fab")
			(hide yes)
			(effects
				(font
					(size 1 1)
					(thickness 0.15)
				)
			)
		)
		(sheetname "USB PHY")
		(sheetfile "usb-phy.kicad_sch")
		(attr smd)
		(fp_line
			(start -2.62 2.648)
			(end -2.62 2.249)
			(stroke
				(width 0.15)
				(type solid)
			)
			(layer "F.SilkS")
		)
		(fp_line
			(start -2.221 -2.551)
			(end -2.62 -2.149)
			(stroke
				(width 0.15)
				(type solid)
			)
			(layer "F.SilkS")
		)
		(fp_line
			(start -2.221 2.648)
			(end -2.62 2.648)
			(stroke
				(width 0.15)
				(type solid)
			)
			(layer "F.SilkS")
		)
		(fp_line
			(start 2.581 -2.551)
			(end 2.178 -2.551)
			(stroke
				(width 0.15)
				(type solid)
			)
			(layer "F.SilkS")
		)
		(fp_line
			(start 2.581 -2.551)
			(end 2.581 -2.149)
			(stroke
				(width 0.15)
				(type solid)
			)
			(layer "F.SilkS")
		)
		(fp_line
			(start 2.581 2.249)
			(end 2.581 2.648)
			(stroke
				(width 0.15)
				(type solid)
			)
			(layer "F.SilkS")
		)
		(fp_line
			(start 2.581 2.648)
			(end 2.178 2.648)
			(stroke
				(width 0.15)
				(type solid)
			)
			(layer "F.SilkS")
		)
		(fp_circle
			(center -3.25 -1.702)
			(end -3.2 -1.702)
			(stroke
				(width 0.15)
				(type solid)
			)
			(fill yes)
			(layer "F.SilkS")
		)
		(fp_rect
			(start -1.446 -0.175)
			(end -0.246 -1.375)
			(stroke
				(width 0.2)
				(type solid)
			)
			(fill yes)
			(layer "F.Paste")
		)
		(fp_rect
			(start -1.446 1.474)
			(end -0.246 0.274)
			(stroke
				(width 0.2)
				(type solid)
			)
			(fill yes)
			(layer "F.Paste")
		)
		(fp_rect
			(start 0.203 -0.175)
			(end 1.403 -1.375)
			(stroke
				(width 0.2)
				(type solid)
			)
			(fill yes)
			(layer "F.Paste")
		)
		(fp_rect
			(start 0.203 1.474)
			(end 1.403 0.274)
			(stroke
				(width 0.2)
				(type solid)
			)
			(fill yes)
			(layer "F.Paste")
		)
		(fp_rect
			(start -2.74 -2.75)
			(end 2.75 2.74)
			(stroke
				(width 0.05)
				(type solid)
			)
			(fill no)
			(layer "F.CrtYd")
		)
		(fp_line
			(start -2.499 -2.299)
			(end -2.298 -2.5)
			(stroke
				(width 0.15)
				(type solid)
			)
			(layer "F.Fab")
		)
		(fp_rect
			(start -2.499 -2.5)
			(end 2.5 2.499)
			(stroke
				(width 0.15)
				(type solid)
			)
			(fill no)
			(layer "F.Fab")
		)
		(pad "1" smd rect
			(at -2.495 -1.702 270)
			(size 0.28 0.85)
			(layers "F.Cu" "F.Mask" "F.Paste")
			(net 1166 "unconnected-(U19-GPIN7-Pad1)")
			(pinfunction "GPIN7")
			(pintype "input+no_connect")
			(solder_mask_margin 0.07)
		)
		(pad "2" smd rect
			(at -2.495 -1.2 270)
			(size 0.28 0.85)
			(layers "F.Cu" "F.Mask" "F.Paste")
			(net 24 "+3V3")
			(pinfunction "VL")
			(pintype "power_in")
			(solder_mask_margin 0.07)
		)
		(pad "3" smd rect
			(at -2.495 -0.701 270)
			(size 0.28 0.85)
			(layers "F.Cu" "F.Mask" "F.Paste")
			(net 1 "GND")
			(pinfunction "GND")
			(pintype "passive")
			(solder_mask_margin 0.07)
		)
		(pad "4" smd rect
			(at -2.495 -0.201 270)
			(size 0.28 0.85)
			(layers "F.Cu" "F.Mask" "F.Paste")
			(net 1167 "unconnected-(U19-GPOUT0-Pad4)")
			(pinfunction "GPOUT0")
			(pintype "output+no_connect")
			(solder_mask_margin 0.07)
		)
		(pad "5" smd rect
			(at -2.495 0.296 270)
			(size 0.28 0.85)
			(layers "F.Cu" "F.Mask" "F.Paste")
			(net 1168 "unconnected-(U19-GPOUT1-Pad5)")
			(pinfunction "GPOUT1")
			(pintype "output+no_connect")
			(solder_mask_margin 0.07)
		)
		(pad "6" smd rect
			(at -2.495 0.8 270)
			(size 0.28 0.85)
			(layers "F.Cu" "F.Mask" "F.Paste")
			(net 1169 "unconnected-(U19-GPOUT2-Pad6)")
			(pinfunction "GPOUT2")
			(pintype "output+no_connect")
			(solder_mask_margin 0.07)
		)
		(pad "7" smd rect
			(at -2.495 1.3 270)
			(size 0.28 0.85)
			(layers "F.Cu" "F.Mask" "F.Paste")
			(net 1170 "unconnected-(U19-GPOUT3-Pad7)")
			(pinfunction "GPOUT3")
			(pintype "output+no_connect")
			(solder_mask_margin 0.07)
		)
		(pad "8" smd rect
			(at -2.495 1.8 270)
			(size 0.28 0.85)
			(layers "F.Cu" "F.Mask" "F.Paste")
			(net 1171 "unconnected-(U19-GPOUT4-Pad8)")
			(pinfunction "GPOUT4")
			(pintype "output+no_connect")
			(solder_mask_margin 0.07)
		)
		(pad "9" smd rect
			(at -1.768 2.523 270)
			(size 0.85 0.28)
			(layers "F.Cu" "F.Mask" "F.Paste")
			(net 1172 "unconnected-(U19-GPOUT5-Pad9)")
			(pinfunction "GPOUT5")
			(pintype "output+no_connect")
			(solder_mask_margin 0.07)
		)
		(pad "10" smd rect
			(at -1.269 2.523 270)
			(size 0.85 0.28)
			(layers "F.Cu" "F.Mask" "F.Paste")
			(net 1173 "unconnected-(U19-GPOUT6-Pad10)")
			(pinfunction "GPOUT6")
			(pintype "output+no_connect")
			(solder_mask_margin 0.07)
		)
		(pad "11" smd rect
			(at -0.772 2.523 270)
			(size 0.85 0.28)
			(layers "F.Cu" "F.Mask" "F.Paste")
			(net 1174 "unconnected-(U19-GPOUT7-Pad11)")
			(pinfunction "GPOUT7")
			(pintype "output+no_connect")
			(solder_mask_margin 0.07)
		)
		(pad "12" smd rect
			(at -0.272 2.523 270)
			(size 0.85 0.28)
			(layers "F.Cu" "F.Mask" "F.Paste")
			(net 496 "/FPGA Bank 12 & 13/USB_HOST.~{RESET}")
			(pinfunction "~{RES}")
			(pintype "input")
			(solder_mask_margin 0.07)
		)
		(pad "13" smd rect
			(at 0.229 2.523 270)
			(size 0.85 0.28)
			(layers "F.Cu" "F.Mask" "F.Paste")
			(net 578 "/FPGA Bank 12 & 13/USB_HOST.CLK")
			(pinfunction "SCLK")
			(pintype "input")
			(solder_mask_margin 0.07)
		)
		(pad "14" smd rect
			(at 0.728 2.523 270)
			(size 0.85 0.28)
			(layers "F.Cu" "F.Mask" "F.Paste")
			(net 893 "/FPGA Bank 12 & 13/USB_HOST.~{CS}")
			(pinfunction "~{SS}")
			(pintype "input")
			(solder_mask_margin 0.07)
		)
		(pad "15" smd rect
			(at 1.23 2.523 270)
			(size 0.85 0.28)
			(layers "F.Cu" "F.Mask" "F.Paste")
			(net 579 "/FPGA Bank 12 & 13/USB_HOST.MISO")
			(pinfunction "MISO")
			(pintype "output")
			(solder_mask_margin 0.07)
		)
		(pad "16" smd rect
			(at 1.73 2.523 270)
			(size 0.85 0.28)
			(layers "F.Cu" "F.Mask" "F.Paste")
			(net 938 "/FPGA Bank 12 & 13/USB_HOST.MOSI")
			(pinfunction "MOSI")
			(pintype "input")
			(solder_mask_margin 0.07)
		)
		(pad "17" smd rect
			(at 2.456 1.8 270)
			(size 0.28 0.85)
			(layers "F.Cu" "F.Mask" "F.Paste")
			(net 580 "/FPGA Bank 12 & 13/USB_HOST.GPX")
			(pinfunction "GPX")
			(pintype "output")
			(solder_mask_margin 0.07)
		)
		(pad "18" smd rect
			(at 2.456 1.3 270)
			(size 0.28 0.85)
			(layers "F.Cu" "F.Mask" "F.Paste")
			(net 495 "/FPGA Bank 12 & 13/USB_HOST.INT")
			(pinfunction "INT")
			(pintype "output")
			(solder_mask_margin 0.07)
		)
		(pad "19" smd rect
			(at 2.456 0.8 270)
			(size 0.28 0.85)
			(layers "F.Cu" "F.Mask" "F.Paste")
			(net 1 "GND")
			(pinfunction "GND")
			(pintype "passive")
			(solder_mask_margin 0.07)
		)
		(pad "20" smd rect
			(at 2.456 0.296 270)
			(size 0.28 0.85)
			(layers "F.Cu" "F.Mask" "F.Paste")
			(net 916 "/USB PHY/USB_HOST_D-")
			(pinfunction "D-")
			(pintype "bidirectional")
			(solder_mask_margin 0.07)
		)
		(pad "21" smd rect
			(at 2.456 -0.201 270)
			(size 0.28 0.85)
			(layers "F.Cu" "F.Mask" "F.Paste")
			(net 917 "/USB PHY/USB_HOST_D+")
			(pinfunction "D+")
			(pintype "bidirectional")
			(solder_mask_margin 0.07)
		)
		(pad "22" smd rect
			(at 2.456 -0.701 270)
			(size 0.28 0.85)
			(layers "F.Cu" "F.Mask" "F.Paste")
			(net 709 "/USB PHY/USB_HOST_VBCOMP")
			(pinfunction "VBCOMP")
			(pintype "input")
			(solder_mask_margin 0.07)
		)
		(pad "23" smd rect
			(at 2.456 -1.2 270)
			(size 0.28 0.85)
			(layers "F.Cu" "F.Mask" "F.Paste")
			(net 24 "+3V3")
			(pinfunction "VCC")
			(pintype "power_in")
			(solder_mask_margin 0.07)
		)
		(pad "24" smd rect
			(at 2.456 -1.702 270)
			(size 0.28 0.85)
			(layers "F.Cu" "F.Mask" "F.Paste")
			(net 706 "/USB PHY/USB_HOST_XI")
			(pinfunction "XI")
			(pintype "input")
			(solder_mask_margin 0.07)
		)
		(pad "25" smd rect
			(at 1.73 -2.426 270)
			(size 0.85 0.28)
			(layers "F.Cu" "F.Mask" "F.Paste")
			(net 708 "/USB PHY/USB_HOST_XO")
			(pinfunction "XO")
			(pintype "output")
			(solder_mask_margin 0.07)
		)
		(pad "26" smd rect
			(at 1.23 -2.426 270)
			(size 0.85 0.28)
			(layers "F.Cu" "F.Mask" "F.Paste")
			(net 1175 "unconnected-(U19-GPIN0-Pad26)")
			(pinfunction "GPIN0")
			(pintype "input+no_connect")
			(solder_mask_margin 0.07)
		)
		(pad "27" smd rect
			(at 0.728 -2.426 270)
			(size 0.85 0.28)
			(layers "F.Cu" "F.Mask" "F.Paste")
			(net 1176 "unconnected-(U19-GPIN1-Pad27)")
			(pinfunction "GPIN1")
			(pintype "input+no_connect")
			(solder_mask_margin 0.07)
		)
		(pad "28" smd rect
			(at 0.229 -2.426 270)
			(size 0.85 0.28)
			(layers "F.Cu" "F.Mask" "F.Paste")
			(net 1177 "unconnected-(U19-GPIN2-Pad28)")
			(pinfunction "GPIN2")
			(pintype "input+no_connect")
			(solder_mask_margin 0.07)
		)
		(pad "29" smd rect
			(at -0.272 -2.426 270)
			(size 0.85 0.28)
			(layers "F.Cu" "F.Mask" "F.Paste")
			(net 1178 "unconnected-(U19-GPIN3-Pad29)")
			(pinfunction "GPIN3")
			(pintype "input+no_connect")
			(solder_mask_margin 0.07)
		)
		(pad "30" smd rect
			(at -0.772 -2.426 270)
			(size 0.85 0.28)
			(layers "F.Cu" "F.Mask" "F.Paste")
			(net 1179 "unconnected-(U19-GPIN4-Pad30)")
			(pinfunction "GPIN4")
			(pintype "input+no_connect")
			(solder_mask_margin 0.07)
		)
		(pad "31" smd rect
			(at -1.269 -2.426 270)
			(size 0.85 0.28)
			(layers "F.Cu" "F.Mask" "F.Paste")
			(net 1180 "unconnected-(U19-GPIN5-Pad31)")
			(pinfunction "GPIN5")
			(pintype "input+no_connect")
			(solder_mask_margin 0.07)
		)
		(pad "32" smd rect
			(at -1.768 -2.426 270)
			(size 0.85 0.28)
			(layers "F.Cu" "F.Mask" "F.Paste")
			(net 1181 "unconnected-(U19-GPIN6-Pad32)")
			(pinfunction "GPIN6")
			(pintype "input+no_connect")
			(solder_mask_margin 0.07)
		)
		(pad "33" smd rect
			(at -0.02 0.048 270)
			(size 3.45 3.45)
			(layers "F.Cu" "F.Mask")
			(net 1 "GND")
			(pinfunction "EP")
			(pintype "passive")
		)
	)
	(footprint "antmicro-footprints:C_0402_1005Metric"
		(layer "F.Cu")
		(at 250.899 101)
		(descr "Capacitor SMD 0402")
		(tags "capacitor SMD 0402")
		(property "Reference" "C242"
			(at -1.449 2.35 0)
			(layer "F.SilkS")
			(effects
				(font
					(size 0.7 0.7)
					(thickness 0.15)
				)
				(justify left bottom)
			)
		)
		(property "Value" "C_100n_0402"
			(at 0 1.169 0)
			(layer "F.Fab")
			(effects
				(font
					(size 0.7 0.7)
					(thickness 0.15)
				)
				(justify left bottom)
			)
		)
		(property "Description" "SMD Multilayer Ceramic Capacitor, 0.1 µF, 50 V, 0402 [1005 Metric], ± 10%, X5R, GRM Series"
			(at 0 0 0)
			(layer "F.Fab")
			(hide yes)
			(effects
				(font
					(size 1.27 1.27)
					(thickness 0.15)
				)
			)
		)
		(property "Author" "Antmicro"
			(at 0 0 0)
			(layer "F.Fab")
			(hide yes)
			(effects
				(font
					(size 1 1)
					(thickness 0.15)
				)
			)
		)
		(property "Dielectric" "X5R"
			(at 0 0 0)
			(layer "F.Fab")
			(hide yes)
			(effects
				(font
					(size 1 1)
					(thickness 0.15)
				)
			)
		)
		(property "License" "Apache-2.0"
			(at 0 0 0)
			(layer "F.Fab")
			(hide yes)
			(effects
				(font
					(size 1 1)
					(thickness 0.15)
				)
			)
		)
		(property "MPN" "GRM155R61H104KE14D"
			(at 0 0 0)
			(layer "F.Fab")
			(hide yes)
			(effects
				(font
					(size 1 1)
					(thickness 0.15)
				)
			)
		)
		(property "Manufacturer" "Murata"
			(at 0 0 0)
			(layer "F.Fab")
			(hide yes)
			(effects
				(font
					(size 1 1)
					(thickness 0.15)
				)
			)
		)
		(property "Val" "100n"
			(at 0 0 0)
			(layer "F.Fab")
			(hide yes)
			(effects
				(font
					(size 1 1)
					(thickness 0.15)
				)
			)
		)
		(property "Voltage" "50V"
			(at 0 0 0)
			(layer "F.Fab")
			(hide yes)
			(effects
				(font
					(size 1 1)
					(thickness 0.15)
				)
			)
		)
		(sheetname "USB PHY")
		(sheetfile "usb-phy.kicad_sch")
		(attr smd)
		(fp_rect
			(start -0.925 -0.47)
			(end 0.925 0.47)
			(stroke
				(width 0.05)
				(type default)
			)
			(fill no)
			(layer "F.CrtYd")
		)
		(fp_line
			(start -0.494 -0.25)
			(end 0.504 -0.25)
			(stroke
				(width 0.15)
				(type solid)
			)
			(layer "F.Fab")
		)
		(fp_line
			(start -0.494 0.248)
			(end -0.494 -0.25)
			(stroke
				(width 0.15)
				(type solid)
			)
			(layer "F.Fab")
		)
		(fp_line
			(start 0.504 -0.25)
			(end 0.504 0.248)
			(stroke
				(width 0.15)
				(type solid)
			)
			(layer "F.Fab")
		)
		(fp_line
			(start 0.504 0.248)
			(end -0.494 0.248)
			(stroke
				(width 0.15)
				(type solid)
			)
			(layer "F.Fab")
		)
		(pad "1" smd roundrect
			(at -0.48 0)
			(size 0.59 0.64)
			(layers "F.Cu" "F.Mask" "F.Paste")
			(roundrect_rratio 0.25)
			(net 1 "GND")
			(pintype "passive")
		)
		(pad "2" smd roundrect
			(at 0.48 0)
			(size 0.59 0.64)
			(layers "F.Cu" "F.Mask" "F.Paste")
			(roundrect_rratio 0.25)
			(net 703 "+5V")
			(pintype "passive")
		)
	)
	(footprint "antmicro-footprints:R_0402_1005Metric"
		(layer "F.Cu")
		(at 199.901 108.249 180)
		(descr "Resistor SMD 0402")
		(tags "resistor SMD 0402")
		(property "Reference" "R155"
			(at -0.899 -0.351 180)
			(layer "F.SilkS")
			(effects
				(font
					(size 0.7 0.7)
					(thickness 0.15)
				)
				(justify left bottom)
			)
		)
		(property "Value" "R_33R_0402"
			(at 0 1.4 180)
			(layer "F.Fab")
			(effects
				(font
					(size 0.7 0.7)
					(thickness 0.15)
				)
				(justify left bottom)
			)
		)
		(property "Description" "SMD Chip Resistor, 33 ohm, ± 1%, 62.5 mW, 0402 [1005 Metric], Thick Film, General Purpose"
			(at 0 0 180)
			(layer "F.Fab")
			(hide yes)
			(effects
				(font
					(size 1.27 1.27)
					(thickness 0.15)
				)
			)
		)
		(property "Author" "Antmicro"
			(at 399.802 216.498 0)
			(layer "F.Fab")
			(hide yes)
			(effects
				(font
					(size 1 1)
					(thickness 0.15)
				)
			)
		)
		(property "License" "Apache-2.0"
			(at 399.802 216.498 0)
			(layer "F.Fab")
			(hide yes)
			(effects
				(font
					(size 1 1)
					(thickness 0.15)
				)
			)
		)
		(property "MPN" "CR0402-FX-33R0GLF"
			(at 399.802 216.498 0)
			(layer "F.Fab")
			(hide yes)
			(effects
				(font
					(size 1 1)
					(thickness 0.15)
				)
			)
		)
		(property "Manufacturer" "Bourns"
			(at 399.802 216.498 0)
			(layer "F.Fab")
			(hide yes)
			(effects
				(font
					(size 1 1)
					(thickness 0.15)
				)
			)
		)
		(property "Tolerance" "1%"
			(at 399.802 216.498 0)
			(layer "F.Fab")
			(hide yes)
			(effects
				(font
					(size 1 1)
					(thickness 0.15)
				)
			)
		)
		(property "Val" "33R"
			(at 399.802 216.498 0)
			(layer "F.Fab")
			(hide yes)
			(effects
				(font
					(size 1 1)
					(thickness 0.15)
				)
			)
		)
		(sheetname "USB PHY")
		(sheetfile "usb-phy.kicad_sch")
		(attr smd)
		(fp_rect
			(start -0.925 -0.47)
			(end 0.925 0.47)
			(stroke
				(width 0.05)
				(type default)
			)
			(fill no)
			(layer "F.CrtYd")
		)
		(fp_rect
			(start -0.5 -0.25)
			(end 0.5 0.25)
			(stroke
				(width 0.15)
				(type solid)
			)
			(fill no)
			(layer "F.Fab")
		)
		(pad "1" smd roundrect
			(at -0.48 0 180)
			(size 0.59 0.64)
			(layers "F.Cu" "F.Mask" "F.Paste")
			(roundrect_rratio 0.25)
			(net 836 "/USB PHY/USB_HOST_CONN_D+")
			(pintype "passive")
		)
		(pad "2" smd roundrect
			(at 0.48 0 180)
			(size 0.59 0.64)
			(layers "F.Cu" "F.Mask" "F.Paste")
			(roundrect_rratio 0.25)
			(net 917 "/USB PHY/USB_HOST_D+")
			(pintype "passive")
		)
	)
)
